(kicad_pcb
	(version 20241229)
	(generator "pcbnew")
	(generator_version "9.0")
	(general
		(thickness 1.711)
		(legacy_teardrops no)
	)
	(paper "A4")
	(title_block
		(title "Antmicro Baseboard for Jetson AGX Thor")
		(date "2026-02-18")
		(rev "1.1.0")
		(company "Antmicro Ltd")
		(comment 1 "www.antmicro.com")
		(comment 9 "footprints 231-235 of 1170")
	)
	(layers
		(0 "F.Cu" signal)
		(4 "In1.Cu" signal)
		(6 "In2.Cu" signal)
		(8 "In3.Cu" signal)
		(10 "In4.Cu" jumper)
		(12 "In5.Cu" signal)
		(14 "In6.Cu" signal)
		(16 "In7.Cu" signal)
		(18 "In8.Cu" signal)
		(2 "B.Cu" signal)
		(9 "F.Adhes" user "F.Adhesive")
		(11 "B.Adhes" user "B.Adhesive")
		(13 "F.Paste" user)
		(15 "B.Paste" user)
		(5 "F.SilkS" user "F.Silkscreen")
		(7 "B.SilkS" user "B.Silkscreen")
		(1 "F.Mask" user)
		(3 "B.Mask" user)
		(17 "Dwgs.User" user "User.Drawings")
		(19 "Cmts.User" user "User.Comments")
		(21 "Eco1.User" user "User.Eco1")
		(23 "Eco2.User" user "User.Eco2")
		(25 "Edge.Cuts" user)
		(27 "Margin" user)
		(31 "F.CrtYd" user "F.Courtyard")
		(29 "B.CrtYd" user "B.Courtyard")
		(35 "F.Fab" user)
		(33 "B.Fab" user)
	)
	(footprint "antmicro-footprints:C_0402_1005Metric"
		(layer "F.Cu")
		(at 211.2 81.3 180)
		(descr "Capacitor SMD 0402")
		(tags "capacitor SMD 0402")
		(property "Reference" "C233"
			(at -0.7 -0.6 0)
			(layer "F.SilkS")
			(effects
				(font
					(size 0.7 0.7)
					(thickness 0.15)
				)
				(justify right top)
			)
		)
		(property "Value" "C_100n_0402"
			(at -1.022927 2.155213 0)
			(layer "F.Fab")
			(effects
				(font
					(size 0.7 0.7)
					(thickness 0.15)
				)
				(justify right top)
			)
		)
		(property "Datasheet" "https://www.murata.com/products/productdetail?partno=GRM155R61H104KE14%23"
			(at 0 0 0)
			(layer "F.Fab")
			(hide yes)
			(effects
				(font
					(size 1.27 1.27)
					(thickness 0.15)
				)
			)
		)
		(property "Description" "SMD Multilayer Ceramic Capacitor, 0.1 µF, 50 V, 0402 [1005 Metric], ± 10%, X5R, GRM Series"
			(at 0 0 0)
			(layer "F.Fab")
			(hide yes)
			(effects
				(font
					(size 1.27 1.27)
					(thickness 0.15)
				)
			)
		)
		(property "MPN" "GRM155R61H104KE14D"
			(at 0 0 180)
			(unlocked yes)
			(layer "F.Fab")
			(hide yes)
			(effects
				(font
					(size 1 1)
					(thickness 0.15)
				)
			)
		)
		(property "Manufacturer" "Murata"
			(at 0 0 180)
			(unlocked yes)
			(layer "F.Fab")
			(hide yes)
			(effects
				(font
					(size 1 1)
					(thickness 0.15)
				)
			)
		)
		(property "Val" "100n"
			(at 0 0 180)
			(unlocked yes)
			(layer "F.Fab")
			(hide yes)
			(effects
				(font
					(size 1 1)
					(thickness 0.15)
				)
			)
		)
		(property "License" "Apache-2.0"
			(at 0 0 180)
			(unlocked yes)
			(layer "F.Fab")
			(hide yes)
			(effects
				(font
					(size 1 1)
					(thickness 0.15)
				)
			)
		)
		(property "Author" "Antmicro"
			(at 0 0 180)
			(unlocked yes)
			(layer "F.Fab")
			(hide yes)
			(effects
				(font
					(size 1 1)
					(thickness 0.15)
				)
			)
		)
		(property "Voltage" "50V"
			(at 0 0 180)
			(unlocked yes)
			(layer "F.Fab")
			(hide yes)
			(effects
				(font
					(size 1 1)
					(thickness 0.15)
				)
			)
		)
		(property "Dielectric" "X5R"
			(at 0 0 180)
			(unlocked yes)
			(layer "F.Fab")
			(hide yes)
			(effects
				(font
					(size 1 1)
					(thickness 0.15)
				)
			)
		)
		(sheetname "/USB Debug, PD/")
		(sheetfile "usb_debug_pd.kicad_sch")
		(attr smd)
		(fp_rect
			(start -0.925 -0.47)
			(end 0.925 0.47)
			(stroke
				(width 0.05)
				(type default)
			)
			(fill no)
			(layer "F.CrtYd")
		)
		(fp_line
			(start 0.504 0.248)
			(end -0.494 0.248)
			(stroke
				(width 0.15)
				(type solid)
			)
			(layer "F.Fab")
		)
		(fp_line
			(start 0.504 -0.25)
			(end 0.504 0.248)
			(stroke
				(width 0.15)
				(type solid)
			)
			(layer "F.Fab")
		)
		(fp_line
			(start -0.494 0.248)
			(end -0.494 -0.25)
			(stroke
				(width 0.15)
				(type solid)
			)
			(layer "F.Fab")
		)
		(fp_line
			(start -0.494 -0.25)
			(end 0.504 -0.25)
			(stroke
				(width 0.15)
				(type solid)
			)
			(layer "F.Fab")
		)
		(fp_text user "License: Apache-2.0"
			(at -0.939 5.799 0)
			(layer "F.Fab")
			(effects
				(font
					(size 0.7 0.7)
					(thickness 0.15)
				)
				(justify right top)
			)
		)
		(fp_text user "Author: Antmicro"
			(at -0.939 3.399 0)
			(layer "F.Fab")
			(effects
				(font
					(size 0.7 0.7)
					(thickness 0.15)
				)
				(justify right top)
			)
		)
		(fp_text user "${REFERENCE}"
			(at -0.939 4.599 0)
			(layer "F.Fab")
			(effects
				(font
					(size 0.7 0.7)
					(thickness 0.15)
				)
				(justify right top)
			)
		)
		(pad "1" smd roundrect
			(at -0.48 0 180)
			(size 0.59 0.64)
			(layers "F.Cu" "F.Mask" "F.Paste")
			(roundrect_rratio 0.25)
			(net 334 "/USB Debug, PD/FTDI_3V3")
			(pintype "passive")
		)
		(pad "2" smd roundrect
			(at 0.48 0 180)
			(size 0.59 0.64)
			(layers "F.Cu" "F.Mask" "F.Paste")
			(roundrect_rratio 0.25)
			(net 1 "GND")
			(pintype "passive")
		)
	)
	(footprint "antmicro-footprints:R_0402_1005Metric"
		(layer "F.Cu")
		(at 189.3 122.6 90)
		(descr "Resistor SMD 0402")
		(tags "resistor SMD 0402")
		(property "Reference" "R379"
			(at 7.1 -2.4 90)
			(layer "F.SilkS")
			(effects
				(font
					(size 0.7 0.7)
					(thickness 0.15)
				)
				(justify left bottom)
			)
		)
		(property "Value" "R_0R_0402"
			(at -1.011843 1.772047 90)
			(layer "F.Fab")
			(effects
				(font
					(size 0.7 0.7)
					(thickness 0.15)
				)
				(justify left bottom)
			)
		)
		(property "Datasheet" "https://industrial.panasonic.com/cdbs/www-data/pdf/RDA0000/AOA0000C301.pdf"
			(at 0 0 90)
			(layer "F.Fab")
			(hide yes)
			(effects
				(font
					(size 1.27 1.27)
					(thickness 0.15)
				)
			)
		)
		(property "Description" "SMD Chip Resistor, Jumper, 0 ohm, 100 mW, 0402 [1005 Metric], Thick Film, General Purpose"
			(at 0 0 90)
			(layer "F.Fab")
			(hide yes)
			(effects
				(font
					(size 1.27 1.27)
					(thickness 0.15)
				)
			)
		)
		(property "MPN" "ERJ2GE0R00X"
			(at 0 0 90)
			(unlocked yes)
			(layer "F.Fab")
			(hide yes)
			(effects
				(font
					(size 1 1)
					(thickness 0.15)
				)
			)
		)
		(property "Manufacturer" "Panasonic"
			(at 0 0 90)
			(unlocked yes)
			(layer "F.Fab")
			(hide yes)
			(effects
				(font
					(size 1 1)
					(thickness 0.15)
				)
			)
		)
		(property "License" "Apache-2.0"
			(at 0 0 90)
			(unlocked yes)
			(layer "F.Fab")
			(hide yes)
			(effects
				(font
					(size 1 1)
					(thickness 0.15)
				)
			)
		)
		(property "Author" "Antmicro"
			(at 0 0 90)
			(unlocked yes)
			(layer "F.Fab")
			(hide yes)
			(effects
				(font
					(size 1 1)
					(thickness 0.15)
				)
			)
		)
		(property "Val" "0R"
			(at 0 0 90)
			(unlocked yes)
			(layer "F.Fab")
			(hide yes)
			(effects
				(font
					(size 1 1)
					(thickness 0.15)
				)
			)
		)
		(property "Tolerance" "~"
			(at 0 0 90)
			(unlocked yes)
			(layer "F.Fab")
			(hide yes)
			(effects
				(font
					(size 1 1)
					(thickness 0.15)
				)
			)
		)
		(property "Current" "1A"
			(at 0 0 90)
			(unlocked yes)
			(layer "F.Fab")
			(hide yes)
			(effects
				(font
					(size 1 1)
					(thickness 0.15)
				)
			)
		)
		(sheetname "/USB Hub/")
		(sheetfile "usb_hub.kicad_sch")
		(attr smd exclude_from_pos_files exclude_from_bom dnp)
		(fp_rect
			(start -0.925 -0.47)
			(end 0.925 0.47)
			(stroke
				(width 0.05)
				(type default)
			)
			(fill no)
			(layer "F.CrtYd")
		)
		(fp_rect
			(start -0.5 -0.25)
			(end 0.5 0.25)
			(stroke
				(width 0.15)
				(type solid)
			)
			(fill no)
			(layer "F.Fab")
		)
		(fp_text user "${REFERENCE}"
			(at -0.95 3.168 90)
			(layer "F.Fab")
			(effects
				(font
					(size 0.7 0.7)
					(thickness 0.15)
				)
				(justify left bottom)
			)
		)
		(fp_text user "Author: Antmicro"
			(at -0.95 4.169 90)
			(layer "F.Fab")
			(effects
				(font
					(size 0.7 0.7)
					(thickness 0.15)
				)
				(justify left bottom)
			)
		)
		(fp_text user "License: Apache-2.0"
			(at -0.95 5.169 90)
			(layer "F.Fab")
			(effects
				(font
					(size 0.7 0.7)
					(thickness 0.15)
				)
				(justify left bottom)
			)
		)
		(pad "1" smd roundrect
			(at -0.48 0 90)
			(size 0.59 0.64)
			(layers "F.Cu" "F.Mask" "F.Paste")
			(roundrect_rratio 0.25)
			(net 921 "/USB Hub/HUB_SPI_D2")
			(pintype "passive")
		)
		(pad "2" smd roundrect
			(at 0.48 0 90)
			(size 0.59 0.64)
			(layers "F.Cu" "F.Mask" "F.Paste")
			(roundrect_rratio 0.25)
			(net 1166 "/USB Hub/HUB_~{WP}")
			(pintype "passive")
		)
	)
	(footprint "antmicro-footprints:Spacer_Drill4.45mm_H4mm_9774040960R"
		(locked yes)
		(layer "F.Cu")
		(at 155.930532 149.71 90)
		(property "Reference" "H8"
			(at -3.47 -3.58 90)
			(layer "F.SilkS")
			(effects
				(font
					(size 0.7 0.7)
					(thickness 0.15)
				)
				(justify left bottom)
			)
		)
		(property "Value" "Spacer_Drill4.45mm_H4mm_9774040960R"
			(at -3.95 5.05 90)
			(layer "F.Fab")
			(effects
				(font
					(size 0.7 0.7)
					(thickness 0.15)
				)
				(justify left bottom)
			)
		)
		(property "Datasheet" "https://www.we-online.com/components/products/datasheet/9774040960R.pdf"
			(at 0 0 90)
			(layer "F.Fab")
			(effects
				(font
					(size 0.7 0.7)
					(thickness 0.15)
				)
				(justify left bottom)
			)
		)
		(property "Description" "Spacer, SMT, Non Stop, Steel, Swage Round, 6 mm x 4 mm, 3.3 mm Internal, WA-SMST Series"
			(at 0 0 90)
			(layer "F.Fab")
			(effects
				(font
					(size 0.7 0.7)
					(thickness 0.15)
				)
				(justify left bottom)
			)
		)
		(property "Manufacturer" "Würth Elektronik"
			(at 0 0 90)
			(unlocked yes)
			(layer "F.Fab")
			(hide yes)
			(effects
				(font
					(size 1 1)
					(thickness 0.15)
				)
			)
		)
		(property "MPN" "9774040960R"
			(at 0 0 90)
			(unlocked yes)
			(layer "F.Fab")
			(hide yes)
			(effects
				(font
					(size 1 1)
					(thickness 0.15)
				)
			)
		)
		(property "Author" "Antmicro"
			(at 0 0 90)
			(unlocked yes)
			(layer "F.Fab")
			(hide yes)
			(effects
				(font
					(size 1 1)
					(thickness 0.15)
				)
			)
		)
		(property "License" "Apache-2.0"
			(at 0 0 90)
			(unlocked yes)
			(layer "F.Fab")
			(hide yes)
			(effects
				(font
					(size 1 1)
					(thickness 0.15)
				)
			)
		)
		(sheetname "/SoM_Power/")
		(sheetfile "som_power.kicad_sch")
		(attr smd)
		(fp_rect
			(start -3.95 -3.95)
			(end 3.95 3.95)
			(stroke
				(width 0.05)
				(type solid)
			)
			(fill no)
			(layer "F.CrtYd")
		)
		(fp_circle
			(center 0 0)
			(end 3.25 0)
			(stroke
				(width 0.05)
				(type solid)
			)
			(fill no)
			(layer "F.CrtYd")
		)
		(fp_circle
			(center 0 0)
			(end 2.564 0)
			(stroke
				(width 0.15)
				(type solid)
			)
			(fill no)
			(layer "F.Fab")
		)
		(fp_text user "Author: Antmicro"
			(at -3.95 8.65 90)
			(layer "F.Fab")
			(effects
				(font
					(size 0.7 0.7)
					(thickness 0.15)
				)
				(justify left bottom)
			)
		)
		(fp_text user "${REFERENCE}"
			(at -3.95 7.45 90)
			(layer "F.Fab")
			(effects
				(font
					(size 0.7 0.7)
					(thickness 0.15)
				)
				(justify left bottom)
			)
		)
		(fp_text user "License: Apache-2.0"
			(at -3.95 6.25 90)
			(layer "F.Fab")
			(effects
				(font
					(size 0.7 0.7)
					(thickness 0.15)
				)
				(justify left bottom)
			)
		)
		(pad "" smd custom
			(at -2.55 -0.55 212.5)
			(size 0.1 0.1)
			(layers "F.Paste")
			(options
				(clearance outline)
				(anchor circle)
			)
			(primitives
				(gr_arc
					(start 0 0)
					(mid 0.704278 1.28373)
					(end 0.608513 2.744826)
					(width 0.7)
				)
			)
		)
		(pad "" smd custom
			(at -0.55 2.55 302.5)
			(size 0.1 0.1)
			(layers "F.Paste")
			(options
				(clearance outline)
				(anchor circle)
			)
			(primitives
				(gr_arc
					(start 0 0)
					(mid 0.704278 1.28373)
					(end 0.608513 2.744826)
					(width 0.7)
				)
			)
		)
		(pad "" smd custom
			(at 0.55 -2.55 122.5)
			(size 0.1 0.1)
			(layers "F.Paste")
			(options
				(clearance outline)
				(anchor circle)
			)
			(primitives
				(gr_arc
					(start 0 0)
					(mid 0.704278 1.28373)
					(end 0.608513 2.744826)
					(width 0.7)
				)
			)
		)
		(pad "" smd custom
			(at 2.55 0.55 32.5)
			(size 0.1 0.1)
			(layers "F.Paste")
			(options
				(clearance outline)
				(anchor circle)
			)
			(primitives
				(gr_arc
					(start 0 0)
					(mid 0.704278 1.28373)
					(end 0.608513 2.744826)
					(width 0.7)
				)
			)
		)
		(pad "1" thru_hole circle
			(at 0 0 90)
			(size 7.4 7.4)
			(drill 4.45)
			(layers "*.Cu" "*.Mask")
			(remove_unused_layers no)
			(net 1 "GND")
			(pintype "passive")
		)
	)
	(footprint "antmicro-footprints:R_0402_1005Metric"
		(layer "F.Cu")
		(at 156.6 118.4 180)
		(descr "Resistor SMD 0402")
		(tags "resistor SMD 0402")
		(property "Reference" "R359"
			(at -3.6 0.4 0)
			(layer "F.SilkS")
			(effects
				(font
					(size 0.7 0.7)
					(thickness 0.15)
				)
				(justify right top)
			)
		)
		(property "Value" "R_2k2_0402"
			(at -1.011843 1.772047 0)
			(layer "F.Fab")
			(effects
				(font
					(size 0.7 0.7)
					(thickness 0.15)
				)
				(justify right top)
			)
		)
		(property "Datasheet" "https://www.bourns.com/docs/product-datasheets/cr.pdf"
			(at 0 0 0)
			(layer "F.Fab")
			(hide yes)
			(effects
				(font
					(size 1.27 1.27)
					(thickness 0.15)
				)
			)
		)
		(property "Description" "SMD Chip Resistor, 2.2 kohm, ± 1%, 62.5 mW, 0402 [1005 Metric], Thick Film, General Purpose"
			(at 0 0 0)
			(layer "F.Fab")
			(hide yes)
			(effects
				(font
					(size 1.27 1.27)
					(thickness 0.15)
				)
			)
		)
		(property "MPN" "CR0402-FX-2201GLF"
			(at 0 0 180)
			(unlocked yes)
			(layer "F.Fab")
			(hide yes)
			(effects
				(font
					(size 1 1)
					(thickness 0.15)
				)
			)
		)
		(property "Manufacturer" "Bourns"
			(at 0 0 180)
			(unlocked yes)
			(layer "F.Fab")
			(hide yes)
			(effects
				(font
					(size 1 1)
					(thickness 0.15)
				)
			)
		)
		(property "License" "Apache-2.0"
			(at 0 0 180)
			(unlocked yes)
			(layer "F.Fab")
			(hide yes)
			(effects
				(font
					(size 1 1)
					(thickness 0.15)
				)
			)
		)
		(property "Author" "Antmicro"
			(at 0 0 180)
			(unlocked yes)
			(layer "F.Fab")
			(hide yes)
			(effects
				(font
					(size 1 1)
					(thickness 0.15)
				)
			)
		)
		(property "Val" "2k2"
			(at 0 0 180)
			(unlocked yes)
			(layer "F.Fab")
			(hide yes)
			(effects
				(font
					(size 1 1)
					(thickness 0.15)
				)
			)
		)
		(property "Tolerance" "1%"
			(at 0 0 180)
			(unlocked yes)
			(layer "F.Fab")
			(hide yes)
			(effects
				(font
					(size 1 1)
					(thickness 0.15)
				)
			)
		)
		(sheetname "/SoM_IO/")
		(sheetfile "som_io.kicad_sch")
		(attr smd exclude_from_pos_files exclude_from_bom dnp)
		(fp_rect
			(start -0.925 -0.47)
			(end 0.925 0.47)
			(stroke
				(width 0.05)
				(type default)
			)
			(fill no)
			(layer "F.CrtYd")
		)
		(fp_rect
			(start -0.5 -0.25)
			(end 0.5 0.25)
			(stroke
				(width 0.15)
				(type solid)
			)
			(fill no)
			(layer "F.Fab")
		)
		(fp_text user "Author: Antmicro"
			(at -0.95 4.169 0)
			(layer "F.Fab")
			(effects
				(font
					(size 0.7 0.7)
					(thickness 0.15)
				)
				(justify right top)
			)
		)
		(fp_text user "License: Apache-2.0"
			(at -0.95 5.169 0)
			(layer "F.Fab")
			(effects
				(font
					(size 0.7 0.7)
					(thickness 0.15)
				)
				(justify right top)
			)
		)
		(fp_text user "${REFERENCE}"
			(at -0.95 3.168 0)
			(layer "F.Fab")
			(effects
				(font
					(size 0.7 0.7)
					(thickness 0.15)
				)
				(justify right top)
			)
		)
		(pad "1" smd roundrect
			(at -0.48 0 180)
			(size 0.59 0.64)
			(layers "F.Cu" "F.Mask" "F.Paste")
			(roundrect_rratio 0.25)
			(net 11 "+1V8")
			(pintype "passive")
		)
		(pad "2" smd roundrect
			(at 0.48 0 180)
			(size 0.59 0.64)
			(layers "F.Cu" "F.Mask" "F.Paste")
			(roundrect_rratio 0.25)
			(net 60 "/SoM_IO/I2C3_SCL_1V8")
			(pintype "passive")
		)
	)
	(footprint "antmicro-footprints:C_0402_1005Metric"
		(layer "F.Cu")
		(at 94 57.5 180)
		(descr "Capacitor SMD 0402")
		(tags "capacitor SMD 0402")
		(property "Reference" "C223"
			(at -9.75 -0.95 0)
			(layer "F.SilkS")
			(effects
				(font
					(size 0.7 0.7)
					(thickness 0.15)
				)
				(justify right top)
			)
		)
		(property "Value" "C_100n_0402"
			(at -1.022927 2.155213 0)
			(layer "F.Fab")
			(effects
				(font
					(size 0.7 0.7)
					(thickness 0.15)
				)
				(justify right top)
			)
		)
		(property "Datasheet" "https://www.murata.com/products/productdetail?partno=GRM155R61H104KE14%23"
			(at 0 0 0)
			(layer "F.Fab")
			(hide yes)
			(effects
				(font
					(size 1.27 1.27)
					(thickness 0.15)
				)
			)
		)
		(property "Description" "SMD Multilayer Ceramic Capacitor, 0.1 µF, 50 V, 0402 [1005 Metric], ± 10%, X5R, GRM Series"
			(at 0 0 0)
			(layer "F.Fab")
			(hide yes)
			(effects
				(font
					(size 1.27 1.27)
					(thickness 0.15)
				)
			)
		)
		(property "MPN" "GRM155R61H104KE14D"
			(at 0 0 180)
			(unlocked yes)
			(layer "F.Fab")
			(hide yes)
			(effects
				(font
					(size 1 1)
					(thickness 0.15)
				)
			)
		)
		(property "Val" "100n"
			(at 0 0 180)
			(unlocked yes)
			(layer "F.Fab")
			(hide yes)
			(effects
				(font
					(size 1 1)
					(thickness 0.15)
				)
			)
		)
		(property "Voltage" "50V"
			(at 0 0 180)
			(unlocked yes)
			(layer "F.Fab")
			(hide yes)
			(effects
				(font
					(size 1 1)
					(thickness 0.15)
				)
			)
		)
		(property "Dielectric" "X5R"
			(at 0 0 180)
			(unlocked yes)
			(layer "F.Fab")
			(hide yes)
			(effects
				(font
					(size 1 1)
					(thickness 0.15)
				)
			)
		)
		(property "Manufacturer" "Murata"
			(at 0 0 180)
			(unlocked yes)
			(layer "F.Fab")
			(hide yes)
			(effects
				(font
					(size 1 1)
					(thickness 0.15)
				)
			)
		)
		(property "License" "Apache-2.0"
			(at 0 0 180)
			(unlocked yes)
			(layer "F.Fab")
			(hide yes)
			(effects
				(font
					(size 1 1)
					(thickness 0.15)
				)
			)
		)
		(property "Author" "Antmicro"
			(at 0 0 180)
			(unlocked yes)
			(layer "F.Fab")
			(hide yes)
			(effects
				(font
					(size 1 1)
					(thickness 0.15)
				)
			)
		)
		(sheetname "/SoM_Power/")
		(sheetfile "som_power.kicad_sch")
		(attr smd)
		(fp_poly
			(pts
				(xy -0.925 -0.47) (xy -0.925 0.47) (xy 0.925 0.47) (xy 0.925 -0.47)
			)
			(stroke
				(width 0.05)
				(type default)
			)
			(fill no)
			(layer "F.CrtYd")
		)
		(fp_line
			(start 0.504 0.248)
			(end -0.494 0.248)
			(stroke
				(width 0.15)
				(type solid)
			)
			(layer "F.Fab")
		)
		(fp_line
			(start 0.504 -0.25)
			(end 0.504 0.248)
			(stroke
				(width 0.15)
				(type solid)
			)
			(layer "F.Fab")
		)
		(fp_line
			(start -0.494 0.248)
			(end -0.494 -0.25)
			(stroke
				(width 0.15)
				(type solid)
			)
			(layer "F.Fab")
		)
		(fp_line
			(start -0.494 -0.25)
			(end 0.504 -0.25)
			(stroke
				(width 0.15)
				(type solid)
			)
			(layer "F.Fab")
		)
		(fp_text user "License: Apache-2.0"
			(at -0.939 5.799 0)
			(layer "F.Fab")
			(effects
				(font
					(size 0.7 0.7)
					(thickness 0.15)
				)
				(justify right top)
			)
		)
		(fp_text user "${REFERENCE}"
			(at -0.939 4.599 0)
			(layer "F.Fab")
			(effects
				(font
					(size 0.7 0.7)
					(thickness 0.15)
				)
				(justify right top)
			)
		)
		(fp_text user "Author: Antmicro"
			(at -0.939 3.399 0)
			(layer "F.Fab")
			(effects
				(font
					(size 0.7 0.7)
					(thickness 0.15)
				)
				(justify right top)
			)
		)
		(pad "1" smd roundrect
			(at -0.48 0 180)
			(size 0.59 0.64)
			(layers "F.Cu" "F.Mask" "F.Paste")
			(roundrect_rratio 0.25)
			(net 1 "GND")
			(pintype "passive")
		)
		(pad "2" smd roundrect
			(at 0.48 0 180)
			(size 0.59 0.64)
			(layers "F.Cu" "F.Mask" "F.Paste")
			(roundrect_rratio 0.25)
			(net 491 "+5V_AON")
			(pintype "passive")
		)
	)
)
